#ISCELL
  mstr_misc prelim *
  *
#ISCELL
  mstr_symbols design_note *
  *
#ISCELL
  mstr_symbols intel_corp_bpage *
  *
#ISCELL
  mstr_symbols pvddq_ghj *
  page72_i14
#ISCELL
  mstr_symbols pvddq_klm *
  page72_i15
#ISCELL
  mstr_symbols pvccio_cpu1 *
  page72_i17
#ISCELL
  mstr_symbols pvccio_cpu1 *
  page72_i18
#ISCELL
  mstr_symbols pvsa_cpu1 *
  page72_i22
#ISCELL
  mstr_symbols gnd *
  page72_i23
#CELL
  mstr_discrete cap *
  page72_i25
#ISCELL
  mstr_symbols vcc_core *
  page72_i28
#ISCELL
  mstr_symbols vcc_core *
  page72_i29
#CELL
  chpset_lib skx_ext_b *
  page72_i32
#CELL
  chpset_lib skx_ext_b *
  page72_i33
#ISCELL
  mstr_symbols pvpp_ghj *
  page72_i38
#ISCELL
  mstr_symbols vcc_core *
  page72_i39
#ISCELL
  mstr_symbols p3v3_stby *
  page72_i40
